# T6G (Grand Teton) — schematic netlist excerpt (pin names and nets, part order shuffled) for the footprints in the layout excerpt that follows; sources: Cadence DE-HDL packaged netlist, KiCad conversion of 04192023_DAF0TMB3IC0_F0TG_MB_C_brd_V02_OCP.brd

PU288  MP5991GLUZ  MP5991GLU-Z IC  pkg LGA32_TH_0-5_5X5  page 263
  VOUT1  = P12V_AUX
  VOUT2  = P12V_AUX
  D_OC  = HSC_D_OC_2
  \on\  = HSC_ON
  GOK  = HSC_FAULT
  FLT_TYPE  = HSC_FLT_TYPE_2
  NC1  = HSC_NC1_2
  MODE  = HSC_MODE_2
  VIN1  = P12V_PSU
  VIN2  = P12V_PSU
  VIN3  = P12V_PSU
  VIN4  = P12V_PSU
  VIN5  = P12V_PSU
  VIN6  = P12V_PSU
  VIN7  = P12V_PSU
  VIN8  = P12V_PSU
  SCREF_OCWREF  = HSC_SCREF_2
  VTEMP  = HSC_VTEMP
  SS  = HSC_SS
  GND  = AGND_HSC
  VDD33  = HSC_VDD_R_2
  IMON  = HSC_IMON
  CS  = HSC_CS_2
  OCREF  = HSC_OCREF
  VOUT3  = P12V_AUX
  VOUT4  = P12V_AUX
  VOUT5  = P12V_AUX
  VOUT6  = P12V_AUX
  VOUT7  = P12V_AUX
  VOUT8  = P12V_AUX
  VOUT9  = P12V_AUX
  VOUT10  = P12V_AUX
  VIN9  = P12V_PSU

(kicad_pcb
	(version 20260206)
	(generator "pcbnew")
	(generator_version "10.0")
	(general
		(thickness 1.6)
		(legacy_teardrops no)
	)
	(paper "A4")
	(title_block
		(title "04192023_DAF0TMB3IC0_F0TG_MB_C_brd_V02_OCP.brd")
		(comment 1 "Grand Teton / footprints 2866-2866 of 8354")
	)
	(layers
		(0 "F.Cu" signal "TOP")
		(4 "In1.Cu" signal "GND")
		(6 "In2.Cu" signal "IN1")
		(8 "In3.Cu" signal "GND1")
		(10 "In4.Cu" signal "IN2")
		(12 "In5.Cu" signal "GND2")
		(14 "In6.Cu" signal "IN3")
		(16 "In7.Cu" signal "GND3")
		(18 "In8.Cu" signal "VCC")
		(20 "In9.Cu" signal "VCC1")
		(22 "In10.Cu" signal "GND4")
		(24 "In11.Cu" signal "IN4")
		(26 "In12.Cu" signal "GND5")
		(28 "In13.Cu" signal "IN5")
		(30 "In14.Cu" signal "GND6")
		(32 "In15.Cu" signal "IN6")
		(34 "In16.Cu" signal "GND7")
		(2 "B.Cu" signal "BOTTOM")
		(9 "F.Adhes" user "F.Adhesive")
		(11 "B.Adhes" user "B.Adhesive")
		(13 "F.Paste" user "Package Geometry/Pastemask Top")
		(15 "B.Paste" user "Package Geometry/Pastemask Bottom")
		(5 "F.SilkS" user "Ref Des/Silkscreen Top")
		(7 "B.SilkS" user "Ref Des/Silkscreen Bottom")
		(1 "F.Mask" user "Board Geometry/Soldermask Top")
		(3 "B.Mask" user "Board Geometry/Soldermask Bottom")
		(17 "Dwgs.User" user "User.Drawings")
		(19 "Cmts.User" user "User.Comments")
		(21 "Eco1.User" user "User.Eco1")
		(23 "Eco2.User" user "User.Eco2")
		(25 "Edge.Cuts" user "Board Geometry/Outline")
		(27 "Margin" user)
		(31 "F.CrtYd" user "Package Geometry/Place Bound Top")
		(29 "B.CrtYd" user "Package Geometry/Place Bound Bottom")
		(35 "F.Fab" user "Ref Des/Assembly Top")
		(33 "B.Fab" user "Ref Des/Assembly Bottom")
	)
	(footprint ""
		(layer "F.Cu")
		(at 210.204558 -401.920202 180)
		(property "Reference" "PU288"
			(at 2.820924 -5.00888 90)
			(unlocked yes)
			(layer "F.SilkS")
			(effects
				(font
					(size 0.7874 0.5842)
					(thickness 0.1524)
				)
			)
		)
		(property "Value" ""
			(at 0 0 180)
			(layer "F.Fab")
			(effects
				(font
					(size 1.27 1.27)
				)
			)
		)
		(duplicate_pad_numbers_are_jumpers no)
		(fp_line
			(start 2.567686 2.567686)
			(end 2.567686 -2.567686)
			(stroke
				(width 0.1524)
				(type default)
			)
			(layer "F.SilkS")
		)
		(fp_line
			(start 2.567686 -2.567686)
			(end -2.567686 -2.567686)
			(stroke
				(width 0.1524)
				(type default)
			)
			(layer "F.SilkS")
		)
		(fp_line
			(start -2.567686 2.567686)
			(end 2.567686 2.567686)
			(stroke
				(width 0.1524)
				(type default)
			)
			(layer "F.SilkS")
		)
		(fp_line
			(start -2.567686 -2.567686)
			(end -2.567686 2.567686)
			(stroke
				(width 0.1524)
				(type default)
			)
			(layer "F.SilkS")
		)
		(fp_poly
			(pts
				(xy -2.632456 -2.13233) (xy -3.709924 -2.491486) (xy -2.991612 -3.209798)
			)
			(stroke
				(width 0)
				(type default)
			)
			(fill yes)
			(layer "F.SilkS")
		)
		(fp_line
			(start 2.549906 2.549906)
			(end 2.549906 -2.549906)
			(stroke
				(width 0.1)
				(type default)
			)
			(layer "F.Fab")
		)
		(fp_line
			(start 2.549906 -2.549906)
			(end -2.549906 -2.549906)
			(stroke
				(width 0.1)
				(type default)
			)
			(layer "F.Fab")
		)
		(fp_line
			(start -2.549906 2.549906)
			(end 2.549906 2.549906)
			(stroke
				(width 0.1)
				(type default)
			)
			(layer "F.Fab")
		)
		(fp_line
			(start -2.549906 -2.549906)
			(end -2.549906 2.549906)
			(stroke
				(width 0.1)
				(type default)
			)
			(layer "F.Fab")
		)
		(fp_poly
			(pts
				(xy -3.806698 -2.25806) (xy -3.806698 -1.24206) (xy -2.790698 -1.75006)
			)
			(stroke
				(width 0)
				(type default)
			)
			(fill yes)
			(layer "F.Fab")
		)
		(pad "1" smd rect
			(at -2.250186 -1.75006 270)
			(size 0.254 0.3556)
			(layers "F.Cu" "F.Mask" "F.Paste")
			(net "P12V_AUX")
		)
		(pad "2" smd rect
			(at -2.237486 -1.249934 270)
			(size 0.254 0.381)
			(layers "F.Cu" "F.Mask" "F.Paste")
			(net "P12V_AUX")
		)
		(pad "3" smd rect
			(at -2.237486 -0.750062 270)
			(size 0.254 0.381)
			(layers "F.Cu" "F.Mask" "F.Paste")
			(net "HSC_D_OC_2")
		)
		(pad "4" smd rect
			(at -2.237486 -0.249936 270)
			(size 0.254 0.381)
			(layers "F.Cu" "F.Mask" "F.Paste")
			(net "HSC_ON")
		)
		(pad "5" smd rect
			(at -2.237486 0.249936 270)
			(size 0.254 0.381)
			(layers "F.Cu" "F.Mask" "F.Paste")
			(net "HSC_FAULT")
		)
		(pad "6" smd rect
			(at -2.237486 0.750062 270)
			(size 0.254 0.381)
			(layers "F.Cu" "F.Mask" "F.Paste")
			(net "HSC_FLT_TYPE_2")
		)
		(pad "7" smd rect
			(at -2.237486 1.249934 270)
			(size 0.254 0.381)
			(layers "F.Cu" "F.Mask" "F.Paste")
			(net "HSC_NC1_2")
		)
		(pad "8" smd rect
			(at -2.250186 1.75006 270)
			(size 0.254 0.3556)
			(layers "F.Cu" "F.Mask" "F.Paste")
			(net "HSC_MODE_2")
		)
		(pad "9" smd rect
			(at -1.75006 2.250186 180)
			(size 0.254 0.3556)
			(layers "F.Cu" "F.Mask" "F.Paste")
			(net "P12V_PSU")
		)
		(pad "10" smd rect
			(at -1.249934 2.237486 180)
			(size 0.254 0.381)
			(layers "F.Cu" "F.Mask" "F.Paste")
			(net "P12V_PSU")
		)
		(pad "11" smd rect
			(at -0.750062 2.237486 180)
			(size 0.254 0.381)
			(layers "F.Cu" "F.Mask" "F.Paste")
			(net "P12V_PSU")
		)
		(pad "12" smd rect
			(at -0.249936 2.237486 180)
			(size 0.254 0.381)
			(layers "F.Cu" "F.Mask" "F.Paste")
			(net "P12V_PSU")
		)
		(pad "13" smd rect
			(at 0.249936 2.237486 180)
			(size 0.254 0.381)
			(layers "F.Cu" "F.Mask" "F.Paste")
			(net "P12V_PSU")
		)
		(pad "14" smd rect
			(at 0.750062 2.237486 180)
			(size 0.254 0.381)
			(layers "F.Cu" "F.Mask" "F.Paste")
			(net "P12V_PSU")
		)
		(pad "15" smd rect
			(at 1.249934 2.237486 180)
			(size 0.254 0.381)
			(layers "F.Cu" "F.Mask" "F.Paste")
			(net "P12V_PSU")
		)
		(pad "16" smd rect
			(at 1.75006 2.250186 180)
			(size 0.254 0.3556)
			(layers "F.Cu" "F.Mask" "F.Paste")
			(net "P12V_PSU")
		)
		(pad "17" smd rect
			(at 2.250186 1.75006 270)
			(size 0.254 0.3556)
			(layers "F.Cu" "F.Mask" "F.Paste")
			(net "HSC_SCREF_2")
		)
		(pad "18" smd rect
			(at 2.237486 1.249934 270)
			(size 0.254 0.381)
			(layers "F.Cu" "F.Mask" "F.Paste")
			(net "HSC_VTEMP")
		)
		(pad "19" smd rect
			(at 2.237486 0.750062 270)
			(size 0.254 0.381)
			(layers "F.Cu" "F.Mask" "F.Paste")
			(net "HSC_SS")
		)
		(pad "20" smd rect
			(at 2.237486 0.249936 270)
			(size 0.254 0.381)
			(layers "F.Cu" "F.Mask" "F.Paste")
			(net "AGND_HSC")
		)
		(pad "21" smd rect
			(at 2.237486 -0.249936 270)
			(size 0.254 0.381)
			(layers "F.Cu" "F.Mask" "F.Paste")
			(net "HSC_VDD_R_2")
		)
		(pad "22" smd rect
			(at 2.237486 -0.750062 270)
			(size 0.254 0.381)
			(layers "F.Cu" "F.Mask" "F.Paste")
			(net "HSC_IMON")
		)
		(pad "23" smd rect
			(at 2.237486 -1.249934 270)
			(size 0.254 0.381)
			(layers "F.Cu" "F.Mask" "F.Paste")
			(net "HSC_CS_2")
		)
		(pad "24" smd rect
			(at 2.250186 -1.75006 270)
			(size 0.254 0.3556)
			(layers "F.Cu" "F.Mask" "F.Paste")
			(net "HSC_OCREF")
		)
		(pad "25" smd rect
			(at 1.75006 -2.250186 180)
			(size 0.254 0.3556)
			(layers "F.Cu" "F.Mask" "F.Paste")
			(net "P12V_AUX")
		)
		(pad "26" smd rect
			(at 1.249934 -2.237486 180)
			(size 0.254 0.381)
			(layers "F.Cu" "F.Mask" "F.Paste")
			(net "P12V_AUX")
		)
		(pad "27" smd rect
			(at 0.750062 -2.237486 180)
			(size 0.254 0.381)
			(layers "F.Cu" "F.Mask" "F.Paste")
			(net "P12V_AUX")
		)
		(pad "28" smd rect
			(at 0.249936 -2.237486 180)
			(size 0.254 0.381)
			(layers "F.Cu" "F.Mask" "F.Paste")
			(net "P12V_AUX")
		)
		(pad "29" smd rect
			(at -0.249936 -2.237486 180)
			(size 0.254 0.381)
			(layers "F.Cu" "F.Mask" "F.Paste")
			(net "P12V_AUX")
		)
		(pad "30" smd rect
			(at -0.750062 -2.237486 180)
			(size 0.254 0.381)
			(layers "F.Cu" "F.Mask" "F.Paste")
			(net "P12V_AUX")
		)
		(pad "31" smd rect
			(at -1.249934 -2.237486 180)
			(size 0.254 0.381)
			(layers "F.Cu" "F.Mask" "F.Paste")
			(net "P12V_AUX")
		)
		(pad "32" smd rect
			(at -1.75006 -2.250186 180)
			(size 0.254 0.3556)
			(layers "F.Cu" "F.Mask" "F.Paste")
			(net "P12V_AUX")
		)
		(pad "33" smd rect
			(at 0 0 180)
			(size 3.4036 3.4036)
			(layers "F.Cu" "F.Mask" "F.Paste")
			(net "P12V_PSU")
		)
		(zone
			(layer "F.Cu")
			(hatch none 0.5)
			(connect_pads
				(clearance 0)
			)
			(min_thickness 0.25)
			(keepout
				(tracks not_allowed)
				(vias allowed)
				(pads allowed)
				(copperpour not_allowed)
				(footprints allowed)
			)
			(placement
				(enabled no)
				(sheetname "")
			)
			(fill
				(thermal_gap 0.5)
				(thermal_bridge_width 0.5)
				(island_removal_mode 0)
			)
			(polygon
				(pts
					(xy 208.182972 -403.58822) (xy 208.451958 -403.58822) (xy 208.451958 -400.167602) (xy 211.957158 -400.167602)
					(xy 211.957158 -402.428202) (xy 212.200744 -402.428202) (xy 212.200744 -400.472402) (xy 212.226144 -400.472402)
					(xy 212.226144 -399.898616) (xy 211.652358 -399.898616) (xy 211.652358 -399.924016) (xy 208.756758 -399.924016)
					(xy 208.756758 -399.898616) (xy 208.182972 -399.898616) (xy 208.182972 -400.472402) (xy 208.208372 -400.472402)
					(xy 208.208372 -403.368002) (xy 208.182972 -403.368002)
				)
			)
		)
	)
)
